(kicad_pcb
	(version 20260206)
	(generator "pcbnew")
	(generator_version "10.0")
	(general
		(thickness 1.6)
		(legacy_teardrops no)
	)
	(paper "A4")
	(title_block
		(title "Bryce Canyon_IOM_IOC_16318-2_OCP.brd")
		(comment 1 "Bryce Canyon / footprints 763-769 of 1605")
	)
	(layers
		(0 "F.Cu" signal "TOP")
		(4 "In1.Cu" signal "L2GND")
		(6 "In2.Cu" signal "L3")
		(8 "In3.Cu" signal "L4VCC")
		(10 "In4.Cu" signal "L5VCC")
		(12 "In5.Cu" signal "L6")
		(14 "In6.Cu" signal "L7GND")
		(2 "B.Cu" signal "BOTTOM")
		(9 "F.Adhes" user "F.Adhesive")
		(11 "B.Adhes" user "B.Adhesive")
		(13 "F.Paste" user "Package Geometry/Pastemask Top")
		(15 "B.Paste" user "Package Geometry/Pastemask Bottom")
		(5 "F.SilkS" user "Ref Des/Silkscreen Top")
		(7 "B.SilkS" user "Ref Des/Silkscreen Bottom")
		(1 "F.Mask" user "Board Geometry/Soldermask Top")
		(3 "B.Mask" user "Board Geometry/Soldermask Bottom")
		(17 "Dwgs.User" user "User.Drawings")
		(19 "Cmts.User" user "User.Comments")
		(21 "Eco1.User" user "User.Eco1")
		(23 "Eco2.User" user "User.Eco2")
		(25 "Edge.Cuts" user "Board Geometry/Outline")
		(27 "Margin" user)
		(31 "F.CrtYd" user "Package Geometry/Place Bound Top")
		(29 "B.CrtYd" user "Package Geometry/Place Bound Bottom")
		(35 "F.Fab" user "Ref Des/Assembly Top")
		(33 "B.Fab" user "Ref Des/Assembly Bottom")
	)
	(footprint ""
		(layer "F.Cu")
		(at 37.9476 -158.623)
		(property "Reference" "R317"
			(at 0 0 0)
			(layer "F.SilkS")
			(hide yes)
			(effects
				(font
					(size 1.27 1.27)
				)
			)
		)
		(property "Value" "0R2J-2-GP"
			(at 0.064008 -3.993896 0)
			(unlocked yes)
			(layer "F.Fab")
			(hide yes)
			(effects
				(font
					(size 1.016 1.016)
					(thickness 0.1524)
				)
			)
		)
		(property "Device Type" "R402H16"
			(at 0.064008 -5.517896 0)
			(unlocked yes)
			(layer "F.Fab")
			(hide yes)
			(effects
				(font
					(size 1.016 1.016)
					(thickness 0.1524)
				)
			)
		)
		(duplicate_pad_numbers_are_jumpers no)
		(fp_line
			(start -0.508 -0.9398)
			(end -0.508 0.9398)
			(stroke
				(width 0.1524)
				(type default)
			)
			(layer "F.SilkS")
		)
		(fp_line
			(start 0.508 -0.9398)
			(end -0.508 -0.9398)
			(stroke
				(width 0.1524)
				(type default)
			)
			(layer "F.SilkS")
		)
		(fp_rect
			(start -0.508 0.9398)
			(end 0.508 -0.9398)
			(stroke
				(width 0)
				(type default)
			)
			(fill no)
			(layer "F.CrtYd")
		)
		(fp_rect
			(start -0.508 0.9398)
			(end 0.508 -0.9398)
			(stroke
				(width 0)
				(type default)
			)
			(fill no)
			(layer "F.Fab")
		)
		(pad "1" smd custom
			(at 0 -0.4445)
			(size 0.1397 0.1397)
			(layers "F.Cu" "F.Mask" "F.Paste")
			(net "PWM_OUT_ZONE_C")
			(options
				(clearance outline)
				(anchor circle)
			)
			(primitives
				(gr_poly
					(pts
						(arc
							(start -0.1778 -0.2794)
							(mid -0.249642 -0.249642)
							(end -0.2794 -0.1778)
						)
						(arc
							(start -0.2794 0.1778)
							(mid -0.249642 0.249642)
							(end -0.1778 0.2794)
						)
						(arc
							(start 0.1778 0.2794)
							(mid 0.249642 0.249642)
							(end 0.2794 0.1778)
						)
						(arc
							(start 0.2794 -0.1778)
							(mid 0.249642 -0.249642)
							(end 0.1778 -0.2794)
						)
					)
					(width 0)
					(fill yes)
				)
			)
		)
		(pad "2" smd custom
			(at 0 0.4445)
			(size 0.1397 0.1397)
			(layers "F.Cu" "F.Mask" "F.Paste")
			(net "FAN_PWM0_BMC")
			(options
				(clearance outline)
				(anchor circle)
			)
			(primitives
				(gr_poly
					(pts
						(arc
							(start -0.1778 -0.2794)
							(mid -0.249642 -0.249642)
							(end -0.2794 -0.1778)
						)
						(arc
							(start -0.2794 0.1778)
							(mid -0.249642 0.249642)
							(end -0.1778 0.2794)
						)
						(arc
							(start 0.1778 0.2794)
							(mid 0.249642 0.249642)
							(end 0.2794 0.1778)
						)
						(arc
							(start 0.2794 -0.1778)
							(mid 0.249642 -0.249642)
							(end 0.1778 -0.2794)
						)
					)
					(width 0)
					(fill yes)
				)
			)
		)
	)
	(footprint ""
		(layer "F.Cu")
		(at 77.151992 -157.601158 90)
		(property "Reference" "R538"
			(at 0 0 90)
			(layer "F.SilkS")
			(hide yes)
			(effects
				(font
					(size 1.27 1.27)
				)
			)
		)
		(property "Value" "4K64R2F-GP"
			(at 0.064008 -3.993896 90)
			(unlocked yes)
			(layer "F.Fab")
			(hide yes)
			(effects
				(font
					(size 1.016 1.016)
					(thickness 0.1524)
				)
			)
		)
		(property "Device Type" "R402H16"
			(at 0.064008 -5.517896 90)
			(unlocked yes)
			(layer "F.Fab")
			(hide yes)
			(effects
				(font
					(size 1.016 1.016)
					(thickness 0.1524)
				)
			)
		)
		(duplicate_pad_numbers_are_jumpers no)
		(fp_line
			(start 0.508 -0.9398)
			(end -0.508 -0.9398)
			(stroke
				(width 0.1524)
				(type default)
			)
			(layer "F.SilkS")
		)
		(fp_line
			(start -0.508 -0.9398)
			(end -0.508 0.9398)
			(stroke
				(width 0.1524)
				(type default)
			)
			(layer "F.SilkS")
		)
		(fp_rect
			(start -0.508 0.9398)
			(end 0.508 -0.9398)
			(stroke
				(width 0)
				(type default)
			)
			(fill no)
			(layer "F.CrtYd")
		)
		(fp_rect
			(start -0.508 0.9398)
			(end 0.508 -0.9398)
			(stroke
				(width 0)
				(type default)
			)
			(fill no)
			(layer "F.Fab")
		)
		(pad "1" smd custom
			(at 0 -0.4445 90)
			(size 0.1397 0.1397)
			(layers "F.Cu" "F.Mask" "F.Paste")
			(net "TPS74801_P1V15_STBY_FB")
			(options
				(clearance outline)
				(anchor circle)
			)
			(primitives
				(gr_poly
					(pts
						(arc
							(start -0.1778 -0.2794)
							(mid -0.249642 -0.249642)
							(end -0.2794 -0.1778)
						)
						(arc
							(start -0.2794 0.1778)
							(mid -0.249642 0.249642)
							(end -0.1778 0.2794)
						)
						(arc
							(start 0.1778 0.2794)
							(mid 0.249642 0.249642)
							(end 0.2794 0.1778)
						)
						(arc
							(start 0.2794 -0.1778)
							(mid 0.249642 -0.249642)
							(end 0.1778 -0.2794)
						)
					)
					(width 0)
					(fill yes)
				)
			)
		)
		(pad "2" smd custom
			(at 0 0.4445 90)
			(size 0.1397 0.1397)
			(layers "F.Cu" "F.Mask" "F.Paste")
			(net "GND")
			(options
				(clearance outline)
				(anchor circle)
			)
			(primitives
				(gr_poly
					(pts
						(arc
							(start -0.1778 -0.2794)
							(mid -0.249642 -0.249642)
							(end -0.2794 -0.1778)
						)
						(arc
							(start -0.2794 0.1778)
							(mid -0.249642 0.249642)
							(end -0.1778 0.2794)
						)
						(arc
							(start 0.1778 0.2794)
							(mid 0.249642 0.249642)
							(end 0.2794 0.1778)
						)
						(arc
							(start 0.2794 -0.1778)
							(mid 0.249642 -0.249642)
							(end 0.1778 -0.2794)
						)
					)
					(width 0)
					(fill yes)
				)
			)
		)
	)
	(footprint ""
		(layer "F.Cu")
		(at 59.5884 -161.9504 -90)
		(property "Reference" "R407"
			(at 0 0 270)
			(layer "F.SilkS")
			(hide yes)
			(effects
				(font
					(size 1.27 1.27)
				)
			)
		)
		(property "Value" "1K4R2F-1-GP"
			(at 0.064008 -3.993896 270)
			(unlocked yes)
			(layer "F.Fab")
			(hide yes)
			(effects
				(font
					(size 1.016 1.016)
					(thickness 0.1524)
				)
			)
		)
		(property "Device Type" "R402H16"
			(at 0.064008 -5.517896 270)
			(unlocked yes)
			(layer "F.Fab")
			(hide yes)
			(effects
				(font
					(size 1.016 1.016)
					(thickness 0.1524)
				)
			)
		)
		(duplicate_pad_numbers_are_jumpers no)
		(fp_line
			(start -0.508 -0.9398)
			(end -0.508 0.9398)
			(stroke
				(width 0.1524)
				(type default)
			)
			(layer "F.SilkS")
		)
		(fp_line
			(start 0.508 -0.9398)
			(end -0.508 -0.9398)
			(stroke
				(width 0.1524)
				(type default)
			)
			(layer "F.SilkS")
		)
		(fp_rect
			(start -0.508 0.9398)
			(end 0.508 -0.9398)
			(stroke
				(width 0)
				(type default)
			)
			(fill no)
			(layer "F.CrtYd")
		)
		(fp_rect
			(start -0.508 0.9398)
			(end 0.508 -0.9398)
			(stroke
				(width 0)
				(type default)
			)
			(fill no)
			(layer "F.Fab")
		)
		(pad "1" smd custom
			(at 0 -0.4445 270)
			(size 0.1397 0.1397)
			(layers "F.Cu" "F.Mask" "F.Paste")
			(net "P3V3_STBY")
			(options
				(clearance outline)
				(anchor circle)
			)
			(primitives
				(gr_poly
					(pts
						(arc
							(start -0.1778 -0.2794)
							(mid -0.249642 -0.249642)
							(end -0.2794 -0.1778)
						)
						(arc
							(start -0.2794 0.1778)
							(mid -0.249642 0.249642)
							(end -0.1778 0.2794)
						)
						(arc
							(start 0.1778 0.2794)
							(mid 0.249642 0.249642)
							(end 0.2794 0.1778)
						)
						(arc
							(start 0.2794 -0.1778)
							(mid 0.249642 -0.249642)
							(end 0.1778 -0.2794)
						)
					)
					(width 0)
					(fill yes)
				)
			)
		)
		(pad "2" smd custom
			(at 0 0.4445 270)
			(size 0.1397 0.1397)
			(layers "F.Cu" "F.Mask" "F.Paste")
			(net "ADC_P3V3_STBY")
			(options
				(clearance outline)
				(anchor circle)
			)
			(primitives
				(gr_poly
					(pts
						(arc
							(start -0.1778 -0.2794)
							(mid -0.249642 -0.249642)
							(end -0.2794 -0.1778)
						)
						(arc
							(start -0.2794 0.1778)
							(mid -0.249642 0.249642)
							(end -0.1778 0.2794)
						)
						(arc
							(start 0.1778 0.2794)
							(mid 0.249642 0.249642)
							(end 0.2794 0.1778)
						)
						(arc
							(start 0.2794 -0.1778)
							(mid 0.249642 -0.249642)
							(end 0.1778 -0.2794)
						)
					)
					(width 0)
					(fill yes)
				)
			)
		)
	)
	(footprint ""
		(layer "F.Cu")
		(at 180.6321 -45.5422)
		(property "Reference" "R673"
			(at 0 0 0)
			(layer "F.SilkS")
			(hide yes)
			(effects
				(font
					(size 1.27 1.27)
				)
			)
		)
		(property "Value" "10KR2F-2-GP"
			(at 0.064008 -3.993896 0)
			(unlocked yes)
			(layer "F.Fab")
			(hide yes)
			(effects
				(font
					(size 1.016 1.016)
					(thickness 0.1524)
				)
			)
		)
		(property "Device Type" "R402H16"
			(at 0.064008 -5.517896 0)
			(unlocked yes)
			(layer "F.Fab")
			(hide yes)
			(effects
				(font
					(size 1.016 1.016)
					(thickness 0.1524)
				)
			)
		)
		(duplicate_pad_numbers_are_jumpers no)
		(fp_line
			(start -0.508 -0.9398)
			(end -0.508 0.9398)
			(stroke
				(width 0.1524)
				(type default)
			)
			(layer "F.SilkS")
		)
		(fp_line
			(start 0.508 -0.9398)
			(end -0.508 -0.9398)
			(stroke
				(width 0.1524)
				(type default)
			)
			(layer "F.SilkS")
		)
		(fp_rect
			(start -0.508 0.9398)
			(end 0.508 -0.9398)
			(stroke
				(width 0)
				(type default)
			)
			(fill no)
			(layer "F.CrtYd")
		)
		(fp_rect
			(start -0.508 0.9398)
			(end 0.508 -0.9398)
			(stroke
				(width 0)
				(type default)
			)
			(fill no)
			(layer "F.Fab")
		)
		(pad "1" smd custom
			(at 0 -0.4445)
			(size 0.1397 0.1397)
			(layers "F.Cu" "F.Mask" "F.Paste")
			(net "XM_ADDR_8")
			(options
				(clearance outline)
				(anchor circle)
			)
			(primitives
				(gr_poly
					(pts
						(arc
							(start -0.1778 -0.2794)
							(mid -0.249642 -0.249642)
							(end -0.2794 -0.1778)
						)
						(arc
							(start -0.2794 0.1778)
							(mid -0.249642 0.249642)
							(end -0.1778 0.2794)
						)
						(arc
							(start 0.1778 0.2794)
							(mid 0.249642 0.249642)
							(end 0.2794 0.1778)
						)
						(arc
							(start 0.2794 -0.1778)
							(mid 0.249642 -0.249642)
							(end 0.1778 -0.2794)
						)
					)
					(width 0)
					(fill yes)
				)
			)
		)
		(pad "2" smd custom
			(at 0 0.4445)
			(size 0.1397 0.1397)
			(layers "F.Cu" "F.Mask" "F.Paste")
			(net "GND")
			(options
				(clearance outline)
				(anchor circle)
			)
			(primitives
				(gr_poly
					(pts
						(arc
							(start -0.1778 -0.2794)
							(mid -0.249642 -0.249642)
							(end -0.2794 -0.1778)
						)
						(arc
							(start -0.2794 0.1778)
							(mid -0.249642 0.249642)
							(end -0.1778 0.2794)
						)
						(arc
							(start 0.1778 0.2794)
							(mid 0.249642 0.249642)
							(end 0.2794 0.1778)
						)
						(arc
							(start 0.2794 -0.1778)
							(mid 0.249642 -0.249642)
							(end 0.1778 -0.2794)
						)
					)
					(width 0)
					(fill yes)
				)
			)
		)
	)
	(footprint ""
		(layer "F.Cu")
		(at 78.5622 -172.5422 180)
		(property "Reference" "R504"
			(at 0 0 180)
			(layer "F.SilkS")
			(hide yes)
			(effects
				(font
					(size 1.27 1.27)
				)
			)
		)
		(property "Value" "0R5J-5-GP"
			(at 0 -8.9535 180)
			(unlocked yes)
			(layer "F.Fab")
			(hide yes)
			(effects
				(font
					(size 1.27 1.016)
					(thickness 0.1524)
				)
			)
		)
		(property "Device Type" "R805H24"
			(at 0 -10.6299 180)
			(unlocked yes)
			(layer "F.Fab")
			(hide yes)
			(effects
				(font
					(size 1.27 1.016)
					(thickness 0.1524)
				)
			)
		)
		(duplicate_pad_numbers_are_jumpers no)
		(fp_line
			(start 0.889 1.7018)
			(end 0.889 -0.508)
			(stroke
				(width 0.1524)
				(type default)
			)
			(layer "F.SilkS")
		)
		(fp_line
			(start 0.889 -1.7018)
			(end 0.889 -0.381)
			(stroke
				(width 0.1524)
				(type default)
			)
			(layer "F.SilkS")
		)
		(fp_line
			(start 0.889 -1.7018)
			(end -0.889 -1.7018)
			(stroke
				(width 0.1524)
				(type default)
			)
			(layer "F.SilkS")
		)
		(fp_line
			(start -0.889 1.7018)
			(end 0.889 1.7018)
			(stroke
				(width 0.1524)
				(type default)
			)
			(layer "F.SilkS")
		)
		(fp_line
			(start -0.889 0.0762)
			(end -0.889 1.7018)
			(stroke
				(width 0.1524)
				(type default)
			)
			(layer "F.SilkS")
		)
		(fp_line
			(start -0.889 -1.7018)
			(end -0.889 0.2794)
			(stroke
				(width 0.1524)
				(type default)
			)
			(layer "F.SilkS")
		)
		(fp_poly
			(pts
				(xy 0.9652 -1.778) (xy 0.9652 1.778) (xy -0.9652 1.778) (xy -0.9652 -1.778)
			)
			(stroke
				(width 0)
				(type default)
			)
			(fill no)
			(layer "F.CrtYd")
		)
		(fp_rect
			(start -0.9652 1.778)
			(end 0.9652 -1.778)
			(stroke
				(width 0)
				(type default)
			)
			(fill no)
			(layer "F.Fab")
		)
		(pad "1" smd rect
			(at 0 -0.9652 180)
			(size 1.397 1.143)
			(layers "F.Cu" "F.Mask" "F.Paste")
			(net "P2V5_STBY")
		)
		(pad "2" smd rect
			(at 0 0.9652 180)
			(size 1.397 1.143)
			(layers "F.Cu" "F.Mask" "F.Paste")
			(net "TPS74801_P2V5_STBY_OUT")
		)
	)
	(footprint ""
		(layer "F.Cu")
		(at 75.48245 -136.335516)
		(property "Reference" "R54"
			(at 0 0 0)
			(layer "F.SilkS")
			(hide yes)
			(effects
				(font
					(size 1.27 1.27)
				)
			)
		)
		(property "Value" "0R2J-2-GP"
			(at 0.064008 -3.993896 0)
			(unlocked yes)
			(layer "F.Fab")
			(hide yes)
			(effects
				(font
					(size 1.016 1.016)
					(thickness 0.1524)
				)
			)
		)
		(property "Device Type" "R402H16"
			(at 0.064008 -5.517896 0)
			(unlocked yes)
			(layer "F.Fab")
			(hide yes)
			(effects
				(font
					(size 1.016 1.016)
					(thickness 0.1524)
				)
			)
		)
		(duplicate_pad_numbers_are_jumpers no)
		(fp_line
			(start -0.508 -0.9398)
			(end -0.508 0.9398)
			(stroke
				(width 0.1524)
				(type default)
			)
			(layer "F.SilkS")
		)
		(fp_line
			(start 0.508 -0.9398)
			(end -0.508 -0.9398)
			(stroke
				(width 0.1524)
				(type default)
			)
			(layer "F.SilkS")
		)
		(fp_rect
			(start -0.508 0.9398)
			(end 0.508 -0.9398)
			(stroke
				(width 0)
				(type default)
			)
			(fill no)
			(layer "F.CrtYd")
		)
		(fp_rect
			(start -0.508 0.9398)
			(end 0.508 -0.9398)
			(stroke
				(width 0)
				(type default)
			)
			(fill no)
			(layer "F.Fab")
		)
		(pad "1" smd custom
			(at 0 -0.4445)
			(size 0.1397 0.1397)
			(layers "F.Cu" "F.Mask" "F.Paste")
			(net "D_FLIP_D")
			(options
				(clearance outline)
				(anchor circle)
			)
			(primitives
				(gr_poly
					(pts
						(arc
							(start -0.1778 -0.2794)
							(mid -0.249642 -0.249642)
							(end -0.2794 -0.1778)
						)
						(arc
							(start -0.2794 0.1778)
							(mid -0.249642 0.249642)
							(end -0.1778 0.2794)
						)
						(arc
							(start 0.1778 0.2794)
							(mid 0.249642 0.249642)
							(end 0.2794 0.1778)
						)
						(arc
							(start 0.2794 -0.1778)
							(mid 0.249642 -0.249642)
							(end 0.1778 -0.2794)
						)
					)
					(width 0)
					(fill yes)
				)
			)
		)
		(pad "2" smd custom
			(at 0 0.4445)
			(size 0.1397 0.1397)
			(layers "F.Cu" "F.Mask" "F.Paste")
			(net "D_FLIP_Q#")
			(options
				(clearance outline)
				(anchor circle)
			)
			(primitives
				(gr_poly
					(pts
						(arc
							(start -0.1778 -0.2794)
							(mid -0.249642 -0.249642)
							(end -0.2794 -0.1778)
						)
						(arc
							(start -0.2794 0.1778)
							(mid -0.249642 0.249642)
							(end -0.1778 0.2794)
						)
						(arc
							(start 0.1778 0.2794)
							(mid 0.249642 0.249642)
							(end 0.2794 0.1778)
						)
						(arc
							(start 0.2794 -0.1778)
							(mid 0.249642 -0.249642)
							(end 0.1778 -0.2794)
						)
					)
					(width 0)
					(fill yes)
				)
			)
		)
	)
	(footprint ""
		(layer "F.Cu")
		(at 8.8392 -139.573 90)
		(property "Reference" "R217"
			(at 0 0 90)
			(layer "F.SilkS")
			(hide yes)
			(effects
				(font
					(size 1.27 1.27)
				)
			)
		)
		(property "Value" "120R2F-GP"
			(at 0.064008 -3.993896 90)
			(unlocked yes)
			(layer "F.Fab")
			(hide yes)
			(effects
				(font
					(size 1.016 1.016)
					(thickness 0.1524)
				)
			)
		)
		(property "Device Type" "R402H16"
			(at 0.064008 -5.517896 90)
			(unlocked yes)
			(layer "F.Fab")
			(hide yes)
			(effects
				(font
					(size 1.016 1.016)
					(thickness 0.1524)
				)
			)
		)
		(duplicate_pad_numbers_are_jumpers no)
		(fp_line
			(start 0.508 -0.9398)
			(end -0.508 -0.9398)
			(stroke
				(width 0.1524)
				(type default)
			)
			(layer "F.SilkS")
		)
		(fp_line
			(start -0.508 -0.9398)
			(end -0.508 0.9398)
			(stroke
				(width 0.1524)
				(type default)
			)
			(layer "F.SilkS")
		)
		(fp_rect
			(start -0.508 0.9398)
			(end 0.508 -0.9398)
			(stroke
				(width 0)
				(type default)
			)
			(fill no)
			(layer "F.CrtYd")
		)
		(fp_rect
			(start -0.508 0.9398)
			(end 0.508 -0.9398)
			(stroke
				(width 0)
				(type default)
			)
			(fill no)
			(layer "F.Fab")
		)
		(pad "1" smd custom
			(at 0 -0.4445 90)
			(size 0.1397 0.1397)
			(layers "F.Cu" "F.Mask" "F.Paste")
			(net "GND")
			(options
				(clearance outline)
				(anchor circle)
			)
			(primitives
				(gr_poly
					(pts
						(arc
							(start -0.1778 -0.2794)
							(mid -0.249642 -0.249642)
							(end -0.2794 -0.1778)
						)
						(arc
							(start -0.2794 0.1778)
							(mid -0.249642 0.249642)
							(end -0.1778 0.2794)
						)
						(arc
							(start 0.1778 0.2794)
							(mid 0.249642 0.249642)
							(end 0.2794 0.1778)
						)
						(arc
							(start 0.2794 -0.1778)
							(mid 0.249642 -0.249642)
							(end 0.1778 -0.2794)
						)
					)
					(width 0)
					(fill yes)
				)
			)
		)
		(pad "2" smd custom
			(at 0 0.4445 90)
			(size 0.1397 0.1397)
			(layers "F.Cu" "F.Mask" "F.Paste")
			(net "MEMBG_0")
			(options
				(clearance outline)
				(anchor circle)
			)
			(primitives
				(gr_poly
					(pts
						(arc
							(start -0.1778 -0.2794)
							(mid -0.249642 -0.249642)
							(end -0.2794 -0.1778)
						)
						(arc
							(start -0.2794 0.1778)
							(mid -0.249642 0.249642)
							(end -0.1778 0.2794)
						)
						(arc
							(start 0.1778 0.2794)
							(mid 0.249642 0.249642)
							(end 0.2794 0.1778)
						)
						(arc
							(start 0.2794 -0.1778)
							(mid 0.249642 -0.249642)
							(end 0.1778 -0.2794)
						)
					)
					(width 0)
					(fill yes)
				)
			)
		)
	)
)
